(kicad_pcb
	(version 20260206)
	(generator "pcbnew")
	(generator_version "10.0")
	(general
		(thickness 1.6)
		(legacy_teardrops no)
	)
	(paper "A4")
	(title_block
		(title "timecard-production-celestica-r4006 — R4006-B0001-02_R01.brd")
		(comment 1 "Time Appliance Project (Time Card) / footprints 439-442 of 1113")
	)
	(layers
		(0 "F.Cu" signal "TOP")
		(4 "In1.Cu" signal "L02_GND1")
		(6 "In2.Cu" signal "L03_SIG1")
		(8 "In3.Cu" signal "L04_GND2")
		(10 "In4.Cu" signal "L05_VCC1")
		(12 "In5.Cu" signal "L06_VCC2")
		(14 "In6.Cu" signal "L07_GND3")
		(16 "In7.Cu" signal "L08_SIG2")
		(18 "In8.Cu" signal "L09_GND4")
		(2 "B.Cu" signal "BOTTOM")
		(9 "F.Adhes" user "F.Adhesive")
		(11 "B.Adhes" user "B.Adhesive")
		(13 "F.Paste" user "Package Geometry/Pastemask Top")
		(15 "B.Paste" user "Package Geometry/Pastemask Bottom")
		(5 "F.SilkS" user "Ref Des/Silkscreen Top")
		(7 "B.SilkS" user "Ref Des/Silkscreen Bottom")
		(1 "F.Mask" user "Board Geometry/Soldermask Top")
		(3 "B.Mask" user "Board Geometry/Soldermask Bottom")
		(17 "Dwgs.User" user "User.Drawings")
		(19 "Cmts.User" user "User.Comments")
		(21 "Eco1.User" user "User.Eco1")
		(23 "Eco2.User" user "User.Eco2")
		(25 "Edge.Cuts" user "Board Geometry/Outline")
		(27 "Margin" user)
		(31 "F.CrtYd" user "Package Geometry/Place Bound Top")
		(29 "B.CrtYd" user "Package Geometry/Place Bound Bottom")
		(35 "F.Fab" user "Ref Des/Assembly Top")
		(33 "B.Fab" user "Ref Des/Assembly Bottom")
	)
	(footprint ""
		(layer "F.Cu")
		(at 18.1356 -57.7342 -90)
		(property "Reference" "C313"
			(at -1.54305 1.3716 0)
			(unlocked yes)
			(layer "F.SilkS")
			(effects
				(font
					(size 0.635 0.4064)
					(thickness 0.1524)
				)
			)
		)
		(property "Value" "VAL*"
			(at 0.0762 2.067306 270)
			(unlocked yes)
			(layer "F.Fab")
			(hide yes)
			(effects
				(font
					(size 0.7874 0.5842)
					(thickness 0.1524)
				)
			)
		)
		(property "Tolerance" "TOL*"
			(at 0.0762 3.032506 270)
			(unlocked yes)
			(layer "Cmts.User")
			(hide yes)
			(effects
				(font
					(size 0.7874 0.5842)
					(thickness 0.1524)
				)
			)
		)
		(property "User Part Number" "PARTNUM*"
			(at 0.1016 4.023106 270)
			(unlocked yes)
			(layer "Cmts.User")
			(hide yes)
			(effects
				(font
					(size 0.7874 0.5842)
					(thickness 0.1524)
				)
			)
		)
		(property "Device Type" "CAPACITOR-G105-0B104-CK,0.1UF,A"
			(at 0.0508 1.127506 270)
			(unlocked yes)
			(layer "F.Fab")
			(hide yes)
			(effects
				(font
					(size 0.7874 0.5842)
					(thickness 0.1524)
				)
			)
		)
		(duplicate_pad_numbers_are_jumpers no)
		(fp_line
			(start -1.143 0.5588)
			(end 1.143 0.5588)
			(stroke
				(width 0.1)
				(type default)
			)
			(layer "F.SilkS")
		)
		(fp_line
			(start 1.143 0.5588)
			(end 1.143 -0.5588)
			(stroke
				(width 0.1)
				(type default)
			)
			(layer "F.SilkS")
		)
		(fp_line
			(start -1.143 -0.5588)
			(end -1.143 0.5588)
			(stroke
				(width 0.1)
				(type default)
			)
			(layer "F.SilkS")
		)
		(fp_line
			(start 1.143 -0.5588)
			(end -1.143 -0.5588)
			(stroke
				(width 0.1)
				(type default)
			)
			(layer "F.SilkS")
		)
		(fp_poly
			(pts
				(xy -1.143 0.5588) (xy 1.143 0.5588) (xy 1.143 -0.5588) (xy -1.143 -0.5588)
			)
			(stroke
				(width 0)
				(type default)
			)
			(fill no)
			(layer "F.CrtYd")
		)
		(fp_line
			(start -0.508 0.3048)
			(end 0.508 0.3048)
			(stroke
				(width 0.1)
				(type default)
			)
			(layer "F.Fab")
		)
		(fp_line
			(start 0.508 0.3048)
			(end 0.508 -0.3048)
			(stroke
				(width 0.1)
				(type default)
			)
			(layer "F.Fab")
		)
		(fp_line
			(start -0.508 -0.3048)
			(end -0.508 0.3048)
			(stroke
				(width 0.1)
				(type default)
			)
			(layer "F.Fab")
		)
		(fp_line
			(start 0.508 -0.3048)
			(end -0.508 -0.3048)
			(stroke
				(width 0.1)
				(type default)
			)
			(layer "F.Fab")
		)
		(pad "1" smd rect
			(at -0.5334 0 270)
			(size 0.7112 0.6096)
			(layers "F.Cu" "F.Mask" "F.Paste")
			(net "XP1R8V_ICP10100")
		)
		(pad "2" smd rect
			(at 0.5334 0 270)
			(size 0.7112 0.6096)
			(layers "F.Cu" "F.Mask" "F.Paste")
			(net "SG")
		)
		(zone
			(layer "F.Cu")
			(hatch none 0.5)
			(connect_pads
				(clearance 0)
			)
			(min_thickness 0.25)
			(keepout
				(tracks allowed)
				(vias not_allowed)
				(pads allowed)
				(copperpour not_allowed)
				(footprints allowed)
			)
			(placement
				(enabled no)
				(sheetname "")
			)
			(fill
				(thermal_gap 0.5)
				(thermal_bridge_width 0.5)
				(island_removal_mode 0)
			)
			(polygon
				(pts
					(xy 17.8308 -57.8104) (xy 17.8308 -57.658) (xy 18.4404 -57.658) (xy 18.4404 -57.8104)
				)
			)
		)
		(zone
			(layer "F.Cu")
			(hatch none 0.5)
			(connect_pads
				(clearance 0)
			)
			(min_thickness 0.25)
			(keepout
				(tracks not_allowed)
				(vias allowed)
				(pads allowed)
				(copperpour not_allowed)
				(footprints allowed)
			)
			(placement
				(enabled no)
				(sheetname "")
			)
			(fill
				(thermal_gap 0.5)
				(thermal_bridge_width 0.5)
				(island_removal_mode 0)
			)
			(polygon
				(pts
					(xy 17.8308 -57.8104) (xy 17.8308 -57.658) (xy 18.4404 -57.658) (xy 18.4404 -57.8104)
				)
			)
		)
	)
	(footprint ""
		(layer "F.Cu")
		(at 41.656 -83.058 180)
		(property "Reference" "CR1"
			(at 0.635 3.00863 0)
			(unlocked yes)
			(layer "F.SilkS")
			(effects
				(font
					(size 0.7874 0.5842)
					(thickness 0.1524)
				)
			)
		)
		(property "Value" ""
			(at 0 0 180)
			(layer "F.Fab")
			(effects
				(font
					(size 1.27 1.27)
				)
			)
		)
		(property "Device Type" "DIODE_2F-G122-10186-01"
			(at 0 2.037842 180)
			(unlocked yes)
			(layer "F.Fab")
			(hide yes)
			(effects
				(font
					(size 0.7874 0.5842)
					(thickness 0.000001)
				)
			)
		)
		(property "User Part Number" "PARTNUM*"
			(at 0 3.231642 180)
			(unlocked yes)
			(layer "Cmts.User")
			(hide yes)
			(effects
				(font
					(size 0.7874 0.5842)
					(thickness 0.000001)
				)
			)
		)
		(duplicate_pad_numbers_are_jumpers no)
		(fp_line
			(start 1.608074 0.928878)
			(end -1.608074 0.928878)
			(stroke
				(width 0.1)
				(type default)
			)
			(layer "F.SilkS")
		)
		(fp_line
			(start 1.608074 -0.928878)
			(end 1.608074 0.928878)
			(stroke
				(width 0.1)
				(type default)
			)
			(layer "F.SilkS")
		)
		(fp_line
			(start -1.608074 0.928878)
			(end -1.608074 -0.928878)
			(stroke
				(width 0.1)
				(type default)
			)
			(layer "F.SilkS")
		)
		(fp_line
			(start -1.608074 -0.928878)
			(end 1.608074 -0.928878)
			(stroke
				(width 0.1)
				(type default)
			)
			(layer "F.SilkS")
		)
		(fp_poly
			(pts
				(xy -2.116074 -0.928878) (xy -2.116074 0.928878) (xy -1.608074 0.928878) (xy -1.608074 -0.928878)
			)
			(stroke
				(width 0)
				(type default)
			)
			(fill yes)
			(layer "F.SilkS")
		)
		(fp_poly
			(pts
				(xy -2.116074 1.182878) (xy 1.862074 1.182878) (xy 1.862074 -1.182878) (xy -2.116074 -1.182878)
			)
			(stroke
				(width 0)
				(type default)
			)
			(fill no)
			(layer "F.CrtYd")
		)
		(fp_line
			(start 0.899922 0.674878)
			(end -0.899922 0.674878)
			(stroke
				(width 0.1)
				(type default)
			)
			(layer "F.Fab")
		)
		(fp_line
			(start 0.899922 -0.674878)
			(end 0.899922 0.674878)
			(stroke
				(width 0.1)
				(type default)
			)
			(layer "F.Fab")
		)
		(fp_line
			(start -0.899922 0.674878)
			(end -0.899922 -0.674878)
			(stroke
				(width 0.1)
				(type default)
			)
			(layer "F.Fab")
		)
		(fp_line
			(start -0.899922 -0.674878)
			(end 0.899922 -0.674878)
			(stroke
				(width 0.1)
				(type default)
			)
			(layer "F.Fab")
		)
		(fp_poly
			(pts
				(xy -0.899922 -0.674878) (xy -0.899922 0.674878) (xy -0.391922 0.674878) (xy -0.391922 -0.674878)
			)
			(stroke
				(width 0)
				(type default)
			)
			(fill yes)
			(layer "F.Fab")
		)
		(fp_text user "A"
			(at 2.54 1.10363 0)
			(unlocked yes)
			(layer "F.SilkS")
			(effects
				(font
					(size 0.7874 0.5842)
					(thickness 0.1524)
				)
			)
		)
		(fp_text user "C"
			(at -2.413 0.78105 0)
			(unlocked yes)
			(layer "F.SilkS")
			(effects
				(font
					(size 0.635 0.4064)
					(thickness 0.1524)
				)
			)
		)
		(fp_text user "A"
			(at 2.262124 0.156718 0)
			(unlocked yes)
			(layer "F.Fab")
			(effects
				(font
					(size 0.7874 0.5842)
					(thickness 0.1524)
				)
			)
		)
		(fp_text user "C"
			(at -1.905 1.10363 0)
			(unlocked yes)
			(layer "F.Fab")
			(effects
				(font
					(size 0.7874 0.5842)
					(thickness 0.1524)
				)
			)
		)
		(pad "A" smd rect
			(at 1.100074 0 180)
			(size 0.508 0.508)
			(layers "F.Cu" "F.Mask" "F.Paste")
			(net "XP5R0V")
		)
		(pad "C" smd rect
			(at -1.100074 0 180)
			(size 0.508 0.508)
			(layers "F.Cu" "F.Mask" "F.Paste")
			(net "UNNAMED_525_CAPACITOR_I7_1")
		)
	)
	(footprint ""
		(layer "F.Cu")
		(at 36.9824 -103.7844)
		(property "Reference" "C11"
			(at -4.0894 -1.33223 0)
			(unlocked yes)
			(layer "F.SilkS")
			(effects
				(font
					(size 0.7874 0.5842)
					(thickness 0.1524)
				)
			)
		)
		(property "Value" "VAL*"
			(at 0.193548 2.13614 0)
			(unlocked yes)
			(layer "F.Fab")
			(hide yes)
			(effects
				(font
					(size 0.7874 0.5842)
					(thickness 0.1524)
				)
			)
		)
		(property "Tolerance" "TOL*"
			(at 0.216154 3.1496 0)
			(unlocked yes)
			(layer "Cmts.User")
			(hide yes)
			(effects
				(font
					(size 0.7874 0.5842)
					(thickness 0.1524)
				)
			)
		)
		(property "Device Type" "CAPACITOR-G104-0B101-FK,100PF,A"
			(at 0.184404 1.180592 0)
			(unlocked yes)
			(layer "F.Fab")
			(hide yes)
			(effects
				(font
					(size 0.7874 0.5842)
					(thickness 0.1524)
				)
			)
		)
		(property "User Part Number" "PARTNUM*"
			(at 0.216154 4.185666 0)
			(unlocked yes)
			(layer "Cmts.User")
			(hide yes)
			(effects
				(font
					(size 0.7874 0.5842)
					(thickness 0.1524)
				)
			)
		)
		(duplicate_pad_numbers_are_jumpers no)
		(fp_line
			(start -0.671322 -0.4445)
			(end 0.671322 -0.4445)
			(stroke
				(width 0.1)
				(type default)
			)
			(layer "F.SilkS")
		)
		(fp_line
			(start -0.671322 0.4445)
			(end -0.671322 -0.4445)
			(stroke
				(width 0.1)
				(type default)
			)
			(layer "F.SilkS")
		)
		(fp_line
			(start 0.671322 -0.4445)
			(end 0.671322 0.4445)
			(stroke
				(width 0.1)
				(type default)
			)
			(layer "F.SilkS")
		)
		(fp_line
			(start 0.671322 0.4445)
			(end -0.671322 0.4445)
			(stroke
				(width 0.1)
				(type default)
			)
			(layer "F.SilkS")
		)
		(fp_rect
			(start 0.671322 -0.4445)
			(end -0.671322 0.4445)
			(stroke
				(width 0)
				(type default)
			)
			(fill no)
			(layer "F.CrtYd")
		)
		(fp_line
			(start -0.31496 -0.1651)
			(end -0.31496 0.1651)
			(stroke
				(width 0.1)
				(type default)
			)
			(layer "F.Fab")
		)
		(fp_line
			(start -0.31496 0.1651)
			(end 0.31496 0.1651)
			(stroke
				(width 0.1)
				(type default)
			)
			(layer "F.Fab")
		)
		(fp_line
			(start 0.31496 -0.1651)
			(end -0.31496 -0.1651)
			(stroke
				(width 0.1)
				(type default)
			)
			(layer "F.Fab")
		)
		(fp_line
			(start 0.31496 0.1651)
			(end 0.31496 -0.1651)
			(stroke
				(width 0.1)
				(type default)
			)
			(layer "F.Fab")
		)
		(pad "1" smd rect
			(at -0.264922 0)
			(size 0.3048 0.381)
			(layers "F.Cu" "F.Mask" "F.Paste")
			(net "UNNAMED_516_CAPACITOR_I29_1")
		)
		(pad "2" smd rect
			(at 0.264922 0)
			(size 0.3048 0.381)
			(layers "F.Cu" "F.Mask" "F.Paste")
			(net "XP5R0V_FB_R_TO_AGND")
		)
		(zone
			(layer "F.Cu")
			(hatch none 0.5)
			(connect_pads
				(clearance 0)
			)
			(min_thickness 0.25)
			(keepout
				(tracks allowed)
				(vias not_allowed)
				(pads allowed)
				(copperpour not_allowed)
				(footprints allowed)
			)
			(placement
				(enabled no)
				(sheetname "")
			)
			(fill
				(thermal_gap 0.5)
				(thermal_bridge_width 0.5)
				(island_removal_mode 0)
			)
			(polygon
				(pts
					(xy 37.094922 -103.9749) (xy 36.869878 -103.9749) (xy 36.869878 -103.5939) (xy 37.094922 -103.5939)
				)
			)
		)
	)
	(footprint ""
		(layer "F.Cu")
		(at 66.4464 -15.367)
		(property "Reference" "R56"
			(at -0.0254 2.19837 0)
			(unlocked yes)
			(layer "F.SilkS")
			(effects
				(font
					(size 0.7874 0.5842)
					(thickness 0.1524)
				)
			)
		)
		(property "Value" "VAL*"
			(at 0.02032 2.13233 0)
			(unlocked yes)
			(layer "F.Fab")
			(hide yes)
			(effects
				(font
					(size 0.7874 0.5842)
					(thickness 0.1524)
				)
			)
		)
		(property "Tolerance" "TOL*"
			(at 0.044704 3.05435 0)
			(unlocked yes)
			(layer "Cmts.User")
			(hide yes)
			(effects
				(font
					(size 0.7874 0.5842)
					(thickness 0.1524)
				)
			)
		)
		(property "User Part Number" "PARTNUM*"
			(at 0.02032 4.024884 0)
			(unlocked yes)
			(layer "Cmts.User")
			(hide yes)
			(effects
				(font
					(size 0.7874 0.5842)
					(thickness 0.1524)
				)
			)
		)
		(property "Device Type" "RESISTOR-G155-14701-01,4.7KOHMA"
			(at 0.008382 1.210564 0)
			(unlocked yes)
			(layer "F.Fab")
			(hide yes)
			(effects
				(font
					(size 0.7874 0.5842)
					(thickness 0.1524)
				)
			)
		)
		(duplicate_pad_numbers_are_jumpers no)
		(fp_line
			(start -1.143 -0.5588)
			(end -1.143 0.5588)
			(stroke
				(width 0.1)
				(type default)
			)
			(layer "F.SilkS")
		)
		(fp_line
			(start -1.143 0.5588)
			(end 1.143 0.5588)
			(stroke
				(width 0.1)
				(type default)
			)
			(layer "F.SilkS")
		)
		(fp_line
			(start 1.143 -0.5588)
			(end -1.143 -0.5588)
			(stroke
				(width 0.1)
				(type default)
			)
			(layer "F.SilkS")
		)
		(fp_line
			(start 1.143 0.5588)
			(end 1.143 -0.5588)
			(stroke
				(width 0.1)
				(type default)
			)
			(layer "F.SilkS")
		)
		(fp_rect
			(start -1.143 0.5588)
			(end 1.143 -0.5588)
			(stroke
				(width 0)
				(type default)
			)
			(fill no)
			(layer "F.CrtYd")
		)
		(fp_line
			(start -0.508 -0.3048)
			(end -0.508 0.3048)
			(stroke
				(width 0.1)
				(type default)
			)
			(layer "F.Fab")
		)
		(fp_line
			(start -0.508 0.3048)
			(end 0.508 0.3048)
			(stroke
				(width 0.1)
				(type default)
			)
			(layer "F.Fab")
		)
		(fp_line
			(start 0.508 -0.3048)
			(end -0.508 -0.3048)
			(stroke
				(width 0.1)
				(type default)
			)
			(layer "F.Fab")
		)
		(fp_line
			(start 0.508 0.3048)
			(end 0.508 -0.3048)
			(stroke
				(width 0.1)
				(type default)
			)
			(layer "F.Fab")
		)
		(pad "1" smd rect
			(at -0.5334 0)
			(size 0.7112 0.6096)
			(layers "F.Cu" "F.Mask" "F.Paste")
			(net "XP3R3V")
		)
		(pad "2" smd rect
			(at 0.5334 0)
			(size 0.7112 0.6096)
			(layers "F.Cu" "F.Mask" "F.Paste")
			(net "PCIE_CONN_PERST_N")
		)
		(zone
			(layer "F.Cu")
			(hatch none 0.5)
			(connect_pads
				(clearance 0)
			)
			(min_thickness 0.25)
			(keepout
				(tracks allowed)
				(vias not_allowed)
				(pads allowed)
				(copperpour not_allowed)
				(footprints allowed)
			)
			(placement
				(enabled no)
				(sheetname "")
			)
			(fill
				(thermal_gap 0.5)
				(thermal_bridge_width 0.5)
				(island_removal_mode 0)
			)
			(polygon
				(pts
					(xy 66.3702 -15.0622) (xy 66.5226 -15.0622) (xy 66.5226 -15.6718) (xy 66.3702 -15.6718)
				)
			)
		)
	)
)
